# T6G (Grand Teton) — schematic netlist excerpt (pin names and nets, part order shuffled) for the footprints in the layout excerpt that follows; sources: Cadence DE-HDL packaged netlist, KiCad conversion of 04192023_DAF0TMB3IC0_F0TG_MB_C_brd_V02_OCP.brd

PC142  Q_CAP  2.2UF 10V 10% X6S  pkg C0402  page 205 : A = PVDDIO_P0_VCC2 ; B = GND

U134  74LVC2G07DW7  74LVC2G07DW-7 IC  pkg SOT363_0-65_2X1-25XC  page 145
  \1a\  = RST_SMB_E1S_N
  GND  = GND
  \2a\  = RST_SMB_E1S_N
  \2y\  = SMB_PCIE_E1S_ISO_EN_R2
  VCC  = P3V3_AUX
  \1y\  = RST_SMB_BUF_E1S_0_N

(kicad_pcb
	(version 20260206)
	(generator "pcbnew")
	(generator_version "10.0")
	(general
		(thickness 1.6)
		(legacy_teardrops no)
	)
	(paper "A4")
	(title_block
		(title "04192023_DAF0TMB3IC0_F0TG_MB_C_brd_V02_OCP.brd")
		(comment 1 "Grand Teton / footprints 1142-1143 of 8354")
	)
	(layers
		(0 "F.Cu" signal "TOP")
		(4 "In1.Cu" signal "GND")
		(6 "In2.Cu" signal "IN1")
		(8 "In3.Cu" signal "GND1")
		(10 "In4.Cu" signal "IN2")
		(12 "In5.Cu" signal "GND2")
		(14 "In6.Cu" signal "IN3")
		(16 "In7.Cu" signal "GND3")
		(18 "In8.Cu" signal "VCC")
		(20 "In9.Cu" signal "VCC1")
		(22 "In10.Cu" signal "GND4")
		(24 "In11.Cu" signal "IN4")
		(26 "In12.Cu" signal "GND5")
		(28 "In13.Cu" signal "IN5")
		(30 "In14.Cu" signal "GND6")
		(32 "In15.Cu" signal "IN6")
		(34 "In16.Cu" signal "GND7")
		(2 "B.Cu" signal "BOTTOM")
		(9 "F.Adhes" user "F.Adhesive")
		(11 "B.Adhes" user "B.Adhesive")
		(13 "F.Paste" user "Package Geometry/Pastemask Top")
		(15 "B.Paste" user "Package Geometry/Pastemask Bottom")
		(5 "F.SilkS" user "Ref Des/Silkscreen Top")
		(7 "B.SilkS" user "Ref Des/Silkscreen Bottom")
		(1 "F.Mask" user "Board Geometry/Soldermask Top")
		(3 "B.Mask" user "Board Geometry/Soldermask Bottom")
		(17 "Dwgs.User" user "User.Drawings")
		(19 "Cmts.User" user "User.Comments")
		(21 "Eco1.User" user "User.Eco1")
		(23 "Eco2.User" user "User.Eco2")
		(25 "Edge.Cuts" user "Board Geometry/Outline")
		(27 "Margin" user)
		(31 "F.CrtYd" user "Package Geometry/Place Bound Top")
		(29 "B.CrtYd" user "Package Geometry/Place Bound Bottom")
		(35 "F.Fab" user "Ref Des/Assembly Top")
		(33 "B.Fab" user "Ref Des/Assembly Bottom")
	)
	(footprint ""
		(layer "F.Cu")
		(at 288.325306 -349.381572 90)
		(property "Reference" "PC142"
			(at 0 0 90)
			(layer "F.SilkS")
			(hide yes)
			(effects
				(font
					(size 1.27 1.27)
				)
			)
		)
		(property "Value" ""
			(at 0 0 90)
			(layer "F.Fab")
			(effects
				(font
					(size 1.27 1.27)
				)
			)
		)
		(duplicate_pad_numbers_are_jumpers no)
		(fp_line
			(start 0.7874 -0.4064)
			(end 0.7874 0.4064)
			(stroke
				(width 0.1524)
				(type default)
			)
			(layer "F.SilkS")
		)
		(fp_line
			(start -0.7874 -0.4064)
			(end 0.7874 -0.4064)
			(stroke
				(width 0.1524)
				(type default)
			)
			(layer "F.SilkS")
		)
		(fp_line
			(start 0.7874 0.4064)
			(end 0.376428 0.4064)
			(stroke
				(width 0.1524)
				(type default)
			)
			(layer "F.SilkS")
		)
		(fp_line
			(start -0.258572 0.4064)
			(end -0.7874 0.4064)
			(stroke
				(width 0.1524)
				(type default)
			)
			(layer "F.SilkS")
		)
		(fp_line
			(start -0.7874 0.4064)
			(end -0.7874 -0.4064)
			(stroke
				(width 0.1524)
				(type default)
			)
			(layer "F.SilkS")
		)
		(fp_line
			(start -0.12065 -0.305054)
			(end -0.12065 -0.2794)
			(stroke
				(width 0.1)
				(type default)
			)
			(layer "F.Fab")
		)
		(fp_line
			(start -0.67945 -0.305054)
			(end -0.12065 -0.305054)
			(stroke
				(width 0.1)
				(type default)
			)
			(layer "F.Fab")
		)
		(fp_line
			(start 0.67945 -0.3048)
			(end 0.67945 0.3048)
			(stroke
				(width 0.1)
				(type default)
			)
			(layer "F.Fab")
		)
		(fp_line
			(start 0.12065 -0.3048)
			(end 0.67945 -0.3048)
			(stroke
				(width 0.1)
				(type default)
			)
			(layer "F.Fab")
		)
		(fp_line
			(start 0.12065 -0.2794)
			(end 0.12065 -0.3048)
			(stroke
				(width 0.1)
				(type default)
			)
			(layer "F.Fab")
		)
		(fp_line
			(start -0.12065 -0.2794)
			(end 0.12065 -0.2794)
			(stroke
				(width 0.1)
				(type default)
			)
			(layer "F.Fab")
		)
		(fp_line
			(start 0.120396 0.2794)
			(end -0.12065 0.2794)
			(stroke
				(width 0.1)
				(type default)
			)
			(layer "F.Fab")
		)
		(fp_line
			(start -0.12065 0.2794)
			(end -0.12065 0.3048)
			(stroke
				(width 0.1)
				(type default)
			)
			(layer "F.Fab")
		)
		(fp_line
			(start 0.67945 0.3048)
			(end 0.120396 0.3048)
			(stroke
				(width 0.1)
				(type default)
			)
			(layer "F.Fab")
		)
		(fp_line
			(start 0.120396 0.3048)
			(end 0.120396 0.2794)
			(stroke
				(width 0.1)
				(type default)
			)
			(layer "F.Fab")
		)
		(fp_line
			(start -0.12065 0.3048)
			(end -0.67945 0.3048)
			(stroke
				(width 0.1)
				(type default)
			)
			(layer "F.Fab")
		)
		(fp_line
			(start -0.67945 0.3048)
			(end -0.67945 -0.305054)
			(stroke
				(width 0.1)
				(type default)
			)
			(layer "F.Fab")
		)
		(pad "1" smd circle
			(at -0.40005 0 90)
			(size 0 0)
			(layers "F.Cu" "F.Mask" "F.Paste")
			(net "PVDDIO_P0_VCC2")
		)
		(pad "2" smd circle
			(at 0.40005 0 90)
			(size 0 0)
			(layers "F.Cu" "F.Mask" "F.Paste")
			(net "GND")
		)
	)
	(footprint ""
		(layer "F.Cu")
		(at 254.362966 -74.44105)
		(property "Reference" "U134"
			(at -1.4732 -1.768348 0)
			(unlocked yes)
			(layer "F.SilkS")
			(effects
				(font
					(size 0.7874 0.5842)
					(thickness 0.1524)
				)
				(justify left)
			)
		)
		(property "Value" ""
			(at 0 0 0)
			(layer "F.Fab")
			(effects
				(font
					(size 1.27 1.27)
				)
			)
		)
		(duplicate_pad_numbers_are_jumpers no)
		(fp_line
			(start -1.38176 -1.100074)
			(end -1.38176 1.100074)
			(stroke
				(width 0.1524)
				(type default)
			)
			(layer "F.SilkS")
		)
		(fp_line
			(start -1.38176 1.100074)
			(end 1.38176 1.100074)
			(stroke
				(width 0.1524)
				(type default)
			)
			(layer "F.SilkS")
		)
		(fp_line
			(start -0.592074 -1.100074)
			(end -1.38176 -1.100074)
			(stroke
				(width 0.1524)
				(type default)
			)
			(layer "F.SilkS")
		)
		(fp_line
			(start 0 -0.508)
			(end -0.592074 -1.100074)
			(stroke
				(width 0.1524)
				(type default)
			)
			(layer "F.SilkS")
		)
		(fp_line
			(start 0.592074 -1.100074)
			(end 0 -0.508)
			(stroke
				(width 0.1524)
				(type default)
			)
			(layer "F.SilkS")
		)
		(fp_line
			(start 1.38176 -1.100074)
			(end 0.592074 -1.100074)
			(stroke
				(width 0.1524)
				(type default)
			)
			(layer "F.SilkS")
		)
		(fp_line
			(start 1.38176 1.100074)
			(end 1.38176 -1.100074)
			(stroke
				(width 0.1524)
				(type default)
			)
			(layer "F.SilkS")
		)
		(fp_poly
			(pts
				(xy -2.041652 -1.321308) (xy -1.735328 -1.637792) (xy -1.572006 -1.172972)
			)
			(stroke
				(width 0)
				(type default)
			)
			(fill yes)
			(layer "F.SilkS")
		)
		(fp_line
			(start -0.674878 -1.100074)
			(end -0.674878 1.100074)
			(stroke
				(width 0.1)
				(type default)
			)
			(layer "F.Fab")
		)
		(fp_line
			(start -0.674878 1.100074)
			(end 0.674878 1.100074)
			(stroke
				(width 0.1)
				(type default)
			)
			(layer "F.Fab")
		)
		(fp_line
			(start 0.674878 -1.100074)
			(end -0.674878 -1.100074)
			(stroke
				(width 0.1)
				(type default)
			)
			(layer "F.Fab")
		)
		(fp_line
			(start 0.674878 1.100074)
			(end 0.674878 -1.100074)
			(stroke
				(width 0.1)
				(type default)
			)
			(layer "F.Fab")
		)
		(fp_poly
			(pts
				(xy -1.9431 -0.870204) (xy -1.50241 -0.649986) (xy -1.9431 -0.429768)
			)
			(stroke
				(width 0)
				(type default)
			)
			(fill yes)
			(layer "F.Fab")
		)
		(pad "1" smd rect
			(at -0.94996 -0.649986 270)
			(size 0.4318 0.6096)
			(layers "F.Cu" "F.Mask" "F.Paste")
			(net "RST_SMB_E1S_N")
		)
		(pad "2" smd rect
			(at -0.94996 0 270)
			(size 0.4318 0.6096)
			(layers "F.Cu" "F.Mask" "F.Paste")
			(net "GND")
		)
		(pad "3" smd rect
			(at -0.94996 0.649986 270)
			(size 0.4318 0.6096)
			(layers "F.Cu" "F.Mask" "F.Paste")
			(net "RST_SMB_E1S_N")
		)
		(pad "4" smd rect
			(at 0.94996 0.649986 270)
			(size 0.4318 0.6096)
			(layers "F.Cu" "F.Mask" "F.Paste")
			(net "SMB_PCIE_E1S_ISO_EN_R2")
		)
		(pad "5" smd rect
			(at 0.94996 0 270)
			(size 0.4318 0.6096)
			(layers "F.Cu" "F.Mask" "F.Paste")
			(net "P3V3_AUX")
		)
		(pad "6" smd rect
			(at 0.94996 -0.649986 270)
			(size 0.4318 0.6096)
			(layers "F.Cu" "F.Mask" "F.Paste")
			(net "RST_SMB_BUF_E1S_0_N")
		)
	)
)
